(kicad_pcb
	(version 20260206)
	(generator "pcbnew")
	(generator_version "10.0")
	(general
		(thickness 1.6)
		(legacy_teardrops no)
	)
	(paper "A4")
	(title_block
		(title "panther-plus-userver — 13130-1b_20150205.brd")
		(comment 1 "Honey Badger (Wiwynn) / footprint 406 of 1509 (DIMM2), pads 135-141 of 210")
	)
	(layers
		(0 "F.Cu" signal "TOP")
		(4 "In1.Cu" signal "L2")
		(6 "In2.Cu" signal "L3")
		(8 "In3.Cu" signal "L4")
		(10 "In4.Cu" signal "L5")
		(12 "In5.Cu" signal "L6")
		(14 "In6.Cu" signal "L7")
		(16 "In7.Cu" signal "L8")
		(18 "In8.Cu" signal "L9")
		(20 "In9.Cu" signal "L10")
		(22 "In10.Cu" signal "L11")
		(2 "B.Cu" signal "BOTTOM")
		(9 "F.Adhes" user "F.Adhesive")
		(11 "B.Adhes" user "B.Adhesive")
		(13 "F.Paste" user "Package Geometry/Pastemask Top")
		(15 "B.Paste" user "Package Geometry/Pastemask Bottom")
		(5 "F.SilkS" user "Ref Des/Silkscreen Top")
		(7 "B.SilkS" user "Ref Des/Silkscreen Bottom")
		(1 "F.Mask" user "Board Geometry/Soldermask Top")
		(3 "B.Mask" user "Board Geometry/Soldermask Bottom")
		(17 "Dwgs.User" user "User.Drawings")
		(19 "Cmts.User" user "User.Comments")
		(21 "Eco1.User" user "User.Eco1")
		(23 "Eco2.User" user "User.Eco2")
		(25 "Edge.Cuts" user "Board Geometry/Outline")
		(27 "Margin" user)
		(31 "F.CrtYd" user "Package Geometry/Place Bound Top")
		(29 "B.CrtYd" user "Package Geometry/Place Bound Bottom")
		(35 "F.Fab" user "Ref Des/Assembly Top")
		(33 "B.Fab" user "Ref Des/Assembly Bottom")
	)
	(footprint ""
		(layer "F.Cu")
		(at 158.500064 -66.699892 180)
		(property "Reference" "DIMM2"
			(at 0 0 180)
			(layer "F.SilkS")
			(hide yes)
			(effects
				(font
					(size 1.27 1.27)
				)
			)
		)
		(property "Value" "DDR3-204P-174-COLAY-1-GP"
			(at -40.682164 -17.468088 180)
			(unlocked yes)
			(layer "F.Fab")
			(hide yes)
			(effects
				(font
					(size 1.016 1.016)
					(thickness 0.1524)
				)
			)
		)
		(property "Device Type" "AS0A626-H8SN-7H-COLAY-1"
			(at -40.682164 -18.992088 180)
			(unlocked yes)
			(layer "F.Fab")
			(hide yes)
			(effects
				(font
					(size 1.016 1.016)
					(thickness 0.1524)
				)
			)
		)
		(duplicate_pad_numbers_are_jumpers no)
		(pad "133" smd custom
			(at 10.349992 4.106672 180)
			(size 0.1143 0.1143)
			(layers "F.Cu" "F.Mask" "F.Paste")
			(net "M_A_DQ36")
			(options
				(clearance outline)
				(anchor circle)
			)
			(primitives
				(gr_poly
					(pts
						(xy 0 0.9017) (xy -0.03175 0.89916) (xy -0.0635 0.889) (xy -0.09144 0.87376) (xy -0.11684 0.85344)
						(xy -0.13716 0.82804) (xy -0.1524 0.8001) (xy -0.16256 0.76835) (xy -0.1651 0.7366) (xy -0.1651 -0.13462)
						(xy -0.17272 -0.14224) (xy -0.19812 -0.1778) (xy -0.2032 -0.18796) (xy -0.20701 -0.19685) (xy -0.21209 -0.20701)
						(xy -0.2159 -0.21717) (xy -0.21844 -0.22733) (xy -0.22225 -0.23876) (xy -0.22352 -0.24892) (xy -0.22606 -0.25908)
						(xy -0.22733 -0.27051) (xy -0.22733 -0.28067) (xy -0.2286 -0.2921) (xy -0.22733 -0.30353) (xy -0.22733 -0.31369)
						(xy -0.22606 -0.32512) (xy -0.22352 -0.33528) (xy -0.22225 -0.34544) (xy -0.21844 -0.35687) (xy -0.2159 -0.36703)
						(xy -0.21209 -0.37719) (xy -0.20701 -0.38735) (xy -0.2032 -0.39624) (xy -0.19812 -0.4064) (xy -0.17272 -0.44196)
						(xy -0.1651 -0.44958) (xy -0.1651 -0.7366) (xy -0.16256 -0.76835) (xy -0.1524 -0.8001) (xy -0.13716 -0.82804)
						(xy -0.11684 -0.85344) (xy -0.09144 -0.87376) (xy -0.0635 -0.889) (xy -0.03175 -0.89916) (xy 0 -0.9017)
						(xy 0.03175 -0.89916) (xy 0.0635 -0.889) (xy 0.09144 -0.87376) (xy 0.11684 -0.85344) (xy 0.13716 -0.82804)
						(xy 0.1524 -0.8001) (xy 0.16256 -0.76835) (xy 0.1651 -0.7366) (xy 0.1651 -0.44958) (xy 0.17272 -0.44196)
						(xy 0.19812 -0.4064) (xy 0.2032 -0.39624) (xy 0.20701 -0.38735) (xy 0.21209 -0.37719) (xy 0.2159 -0.36703)
						(xy 0.21844 -0.35687) (xy 0.22225 -0.34544) (xy 0.22352 -0.33528) (xy 0.22606 -0.32512) (xy 0.22733 -0.31369)
						(xy 0.22733 -0.30353) (xy 0.2286 -0.2921) (xy 0.22733 -0.28067) (xy 0.22733 -0.27051) (xy 0.22606 -0.25908)
						(xy 0.22352 -0.24892) (xy 0.22225 -0.23876) (xy 0.21844 -0.22733) (xy 0.2159 -0.21717) (xy 0.21209 -0.20701)
						(xy 0.20701 -0.19685) (xy 0.2032 -0.18796) (xy 0.19812 -0.1778) (xy 0.17272 -0.14224) (xy 0.1651 -0.13462)
						(xy 0.1651 0.7366) (xy 0.16256 0.76835) (xy 0.1524 0.8001) (xy 0.13716 0.82804) (xy 0.11684 0.85344)
						(xy 0.09144 0.87376) (xy 0.0635 0.889) (xy 0.03175 0.89916)
					)
					(width 0)
					(fill yes)
				)
			)
		)
		(pad "134" smd custom
			(at 10.649966 -4.106672 180)
			(size 0.1143 0.1143)
			(layers "F.Cu" "F.Mask" "F.Paste")
			(net "M_A_DQ32")
			(options
				(clearance outline)
				(anchor circle)
			)
			(primitives
				(gr_poly
					(pts
						(xy 0 0.9017) (xy -0.03175 0.89916) (xy -0.0635 0.889) (xy -0.09144 0.87376) (xy -0.11684 0.85344)
						(xy -0.13716 0.82804) (xy -0.1524 0.8001) (xy -0.16256 0.76835) (xy -0.1651 0.7366) (xy -0.1651 0.44958)
						(xy -0.17272 0.44196) (xy -0.19812 0.4064) (xy -0.2032 0.39624) (xy -0.20701 0.38735) (xy -0.21209 0.37719)
						(xy -0.2159 0.36703) (xy -0.21844 0.35687) (xy -0.22225 0.34544) (xy -0.22352 0.33528) (xy -0.22606 0.32512)
						(xy -0.22733 0.31369) (xy -0.22733 0.30353) (xy -0.2286 0.2921) (xy -0.22733 0.28067) (xy -0.22733 0.27051)
						(xy -0.22606 0.25908) (xy -0.22352 0.24892) (xy -0.22225 0.23876) (xy -0.21844 0.22733) (xy -0.2159 0.21717)
						(xy -0.21209 0.20701) (xy -0.20701 0.19685) (xy -0.2032 0.18796) (xy -0.19812 0.1778) (xy -0.17272 0.14224)
						(xy -0.1651 0.13462) (xy -0.1651 -0.7366) (xy -0.16256 -0.76835) (xy -0.1524 -0.8001) (xy -0.13716 -0.82804)
						(xy -0.11684 -0.85344) (xy -0.09144 -0.87376) (xy -0.0635 -0.889) (xy -0.03175 -0.89916) (xy 0 -0.9017)
						(xy 0.03175 -0.89916) (xy 0.0635 -0.889) (xy 0.09144 -0.87376) (xy 0.11684 -0.85344) (xy 0.13716 -0.82804)
						(xy 0.1524 -0.8001) (xy 0.16256 -0.76835) (xy 0.1651 -0.7366) (xy 0.1651 0.13462) (xy 0.17272 0.14224)
						(xy 0.19812 0.1778) (xy 0.2032 0.18796) (xy 0.20701 0.19685) (xy 0.21209 0.20701) (xy 0.2159 0.21717)
						(xy 0.21844 0.22733) (xy 0.22225 0.23876) (xy 0.22352 0.24892) (xy 0.22606 0.25908) (xy 0.22733 0.27051)
						(xy 0.22733 0.28067) (xy 0.2286 0.2921) (xy 0.22733 0.30353) (xy 0.22733 0.31369) (xy 0.22606 0.32512)
						(xy 0.22352 0.33528) (xy 0.22225 0.34544) (xy 0.21844 0.35687) (xy 0.2159 0.36703) (xy 0.21209 0.37719)
						(xy 0.20701 0.38735) (xy 0.2032 0.39624) (xy 0.19812 0.4064) (xy 0.17272 0.44196) (xy 0.1651 0.44958)
						(xy 0.1651 0.7366) (xy 0.16256 0.76835) (xy 0.1524 0.8001) (xy 0.13716 0.82804) (xy 0.11684 0.85344)
						(xy 0.09144 0.87376) (xy 0.0635 0.889) (xy 0.03175 0.89916)
					)
					(width 0)
					(fill yes)
				)
			)
		)
		(pad "135" smd custom
			(at 10.94994 4.106672 180)
			(size 0.1143 0.1143)
			(layers "F.Cu" "F.Mask" "F.Paste")
			(net "M_A_DQ37")
			(options
				(clearance outline)
				(anchor circle)
			)
			(primitives
				(gr_poly
					(pts
						(xy 0 0.9017) (xy -0.03175 0.89916) (xy -0.0635 0.889) (xy -0.09144 0.87376) (xy -0.11684 0.85344)
						(xy -0.13716 0.82804) (xy -0.1524 0.8001) (xy -0.16256 0.76835) (xy -0.1651 0.7366) (xy -0.1651 0.11938)
						(xy -0.17272 0.11176) (xy -0.19812 0.0762) (xy -0.2032 0.06604) (xy -0.20701 0.05715) (xy -0.21209 0.04699)
						(xy -0.2159 0.03683) (xy -0.21844 0.02667) (xy -0.22225 0.01524) (xy -0.22352 0.00508) (xy -0.22606 -0.00508)
						(xy -0.22733 -0.01651) (xy -0.22733 -0.02667) (xy -0.2286 -0.0381) (xy -0.22733 -0.04953) (xy -0.22733 -0.05969)
						(xy -0.22606 -0.07112) (xy -0.22352 -0.08128) (xy -0.22225 -0.09144) (xy -0.21844 -0.10287) (xy -0.2159 -0.11303)
						(xy -0.21209 -0.12319) (xy -0.20701 -0.13335) (xy -0.2032 -0.14224) (xy -0.19812 -0.1524) (xy -0.17272 -0.18796)
						(xy -0.1651 -0.19558) (xy -0.1651 -0.7366) (xy -0.16256 -0.76835) (xy -0.1524 -0.8001) (xy -0.13716 -0.82804)
						(xy -0.11684 -0.85344) (xy -0.09144 -0.87376) (xy -0.0635 -0.889) (xy -0.03175 -0.89916) (xy 0 -0.9017)
						(xy 0.03175 -0.89916) (xy 0.0635 -0.889) (xy 0.09144 -0.87376) (xy 0.11684 -0.85344) (xy 0.13716 -0.82804)
						(xy 0.1524 -0.8001) (xy 0.16256 -0.76835) (xy 0.1651 -0.7366) (xy 0.1651 -0.19685) (xy 0.17272 -0.18923)
						(xy 0.17907 -0.18034) (xy 0.18669 -0.17145) (xy 0.19177 -0.16256) (xy 0.19812 -0.15367) (xy 0.20828 -0.13335)
						(xy 0.21971 -0.10287) (xy 0.22225 -0.09271) (xy 0.22479 -0.08128) (xy 0.22606 -0.07112) (xy 0.2286 -0.05969)
						(xy 0.2286 -0.01651) (xy 0.22606 -0.00508) (xy 0.22479 0.00508) (xy 0.22225 0.01651) (xy 0.21971 0.02667)
						(xy 0.20828 0.05715) (xy 0.19812 0.07747) (xy 0.19177 0.08636) (xy 0.18669 0.09525) (xy 0.17907 0.10414)
						(xy 0.17272 0.11303) (xy 0.1651 0.12065) (xy 0.1651 0.7366) (xy 0.16256 0.76835) (xy 0.1524 0.8001)
						(xy 0.13716 0.82804) (xy 0.11684 0.85344) (xy 0.09144 0.87376) (xy 0.0635 0.889) (xy 0.03175 0.89916)
					)
					(width 0)
					(fill yes)
				)
			)
		)
		(pad "136" smd custom
			(at 11.249914 -4.106672 180)
			(size 0.1143 0.1143)
			(layers "F.Cu" "F.Mask" "F.Paste")
			(net "M_A_DQ33")
			(options
				(clearance outline)
				(anchor circle)
			)
			(primitives
				(gr_poly
					(pts
						(xy 0 0.9017) (xy -0.03175 0.89916) (xy -0.0635 0.889) (xy -0.09144 0.87376) (xy -0.11684 0.85344)
						(xy -0.13716 0.82804) (xy -0.1524 0.8001) (xy -0.16256 0.76835) (xy -0.1651 0.7366) (xy -0.1651 0.19685)
						(xy -0.17272 0.18923) (xy -0.17907 0.18034) (xy -0.18669 0.17145) (xy -0.19177 0.16256) (xy -0.19812 0.15367)
						(xy -0.20828 0.13335) (xy -0.21971 0.10287) (xy -0.22225 0.09271) (xy -0.22479 0.08128) (xy -0.22606 0.07112)
						(xy -0.2286 0.05969) (xy -0.2286 0.01651) (xy -0.22606 0.00508) (xy -0.22479 -0.00508) (xy -0.22225 -0.01651)
						(xy -0.21971 -0.02667) (xy -0.20828 -0.05715) (xy -0.19812 -0.07747) (xy -0.19177 -0.08636) (xy -0.18669 -0.09525)
						(xy -0.17907 -0.10414) (xy -0.17272 -0.11303) (xy -0.1651 -0.12065) (xy -0.1651 -0.7366) (xy -0.16256 -0.76835)
						(xy -0.1524 -0.8001) (xy -0.13716 -0.82804) (xy -0.11684 -0.85344) (xy -0.09144 -0.87376) (xy -0.0635 -0.889)
						(xy -0.03175 -0.89916) (xy 0 -0.9017) (xy 0.03175 -0.89916) (xy 0.0635 -0.889) (xy 0.09144 -0.87376)
						(xy 0.11684 -0.85344) (xy 0.13716 -0.82804) (xy 0.1524 -0.8001) (xy 0.16256 -0.76835) (xy 0.1651 -0.7366)
						(xy 0.1651 -0.11938) (xy 0.17272 -0.11176) (xy 0.19812 -0.0762) (xy 0.2032 -0.06604) (xy 0.20701 -0.05715)
						(xy 0.21209 -0.04699) (xy 0.2159 -0.03683) (xy 0.21844 -0.02667) (xy 0.22225 -0.01524) (xy 0.22352 -0.00508)
						(xy 0.22606 0.00508) (xy 0.22733 0.01651) (xy 0.22733 0.02667) (xy 0.2286 0.0381) (xy 0.22733 0.04953)
						(xy 0.22733 0.05969) (xy 0.22606 0.07112) (xy 0.22352 0.08128) (xy 0.22225 0.09144) (xy 0.21844 0.10287)
						(xy 0.2159 0.11303) (xy 0.21209 0.12319) (xy 0.20701 0.13335) (xy 0.2032 0.14224) (xy 0.19812 0.1524)
						(xy 0.17272 0.18796) (xy 0.1651 0.19558) (xy 0.1651 0.7366) (xy 0.16256 0.76835) (xy 0.1524 0.8001)
						(xy 0.13716 0.82804) (xy 0.11684 0.85344) (xy 0.09144 0.87376) (xy 0.0635 0.889) (xy 0.03175 0.89916)
					)
					(width 0)
					(fill yes)
				)
			)
		)
		(pad "137" smd custom
			(at 11.549888 4.106672 180)
			(size 0.1143 0.1143)
			(layers "F.Cu" "F.Mask" "F.Paste")
			(net "GND")
			(options
				(clearance outline)
				(anchor circle)
			)
			(primitives
				(gr_poly
					(pts
						(xy 0 0.9017) (xy -0.03175 0.89916) (xy -0.0635 0.889) (xy -0.09144 0.87376) (xy -0.11684 0.85344)
						(xy -0.13716 0.82804) (xy -0.1524 0.8001) (xy -0.16256 0.76835) (xy -0.1651 0.7366) (xy -0.1651 -0.13462)
						(xy -0.17272 -0.14224) (xy -0.19812 -0.1778) (xy -0.2032 -0.18796) (xy -0.20701 -0.19685) (xy -0.21209 -0.20701)
						(xy -0.2159 -0.21717) (xy -0.21844 -0.22733) (xy -0.22225 -0.23876) (xy -0.22352 -0.24892) (xy -0.22606 -0.25908)
						(xy -0.22733 -0.27051) (xy -0.22733 -0.28067) (xy -0.2286 -0.2921) (xy -0.22733 -0.30353) (xy -0.22733 -0.31369)
						(xy -0.22606 -0.32512) (xy -0.22352 -0.33528) (xy -0.22225 -0.34544) (xy -0.21844 -0.35687) (xy -0.2159 -0.36703)
						(xy -0.21209 -0.37719) (xy -0.20701 -0.38735) (xy -0.2032 -0.39624) (xy -0.19812 -0.4064) (xy -0.17272 -0.44196)
						(xy -0.1651 -0.44958) (xy -0.1651 -0.7366) (xy -0.16256 -0.76835) (xy -0.1524 -0.8001) (xy -0.13716 -0.82804)
						(xy -0.11684 -0.85344) (xy -0.09144 -0.87376) (xy -0.0635 -0.889) (xy -0.03175 -0.89916) (xy 0 -0.9017)
						(xy 0.03175 -0.89916) (xy 0.0635 -0.889) (xy 0.09144 -0.87376) (xy 0.11684 -0.85344) (xy 0.13716 -0.82804)
						(xy 0.1524 -0.8001) (xy 0.16256 -0.76835) (xy 0.1651 -0.7366) (xy 0.1651 -0.44958) (xy 0.17272 -0.44196)
						(xy 0.19812 -0.4064) (xy 0.2032 -0.39624) (xy 0.20701 -0.38735) (xy 0.21209 -0.37719) (xy 0.2159 -0.36703)
						(xy 0.21844 -0.35687) (xy 0.22225 -0.34544) (xy 0.22352 -0.33528) (xy 0.22606 -0.32512) (xy 0.22733 -0.31369)
						(xy 0.22733 -0.30353) (xy 0.2286 -0.2921) (xy 0.22733 -0.28067) (xy 0.22733 -0.27051) (xy 0.22606 -0.25908)
						(xy 0.22352 -0.24892) (xy 0.22225 -0.23876) (xy 0.21844 -0.22733) (xy 0.2159 -0.21717) (xy 0.21209 -0.20701)
						(xy 0.20701 -0.19685) (xy 0.2032 -0.18796) (xy 0.19812 -0.1778) (xy 0.17272 -0.14224) (xy 0.1651 -0.13462)
						(xy 0.1651 0.7366) (xy 0.16256 0.76835) (xy 0.1524 0.8001) (xy 0.13716 0.82804) (xy 0.11684 0.85344)
						(xy 0.09144 0.87376) (xy 0.0635 0.889) (xy 0.03175 0.89916)
					)
					(width 0)
					(fill yes)
				)
			)
		)
		(pad "138" smd custom
			(at 11.850116 -4.106672 180)
			(size 0.1143 0.1143)
			(layers "F.Cu" "F.Mask" "F.Paste")
			(net "GND")
			(options
				(clearance outline)
				(anchor circle)
			)
			(primitives
				(gr_poly
					(pts
						(xy 0 0.9017) (xy -0.03175 0.89916) (xy -0.0635 0.889) (xy -0.09144 0.87376) (xy -0.11684 0.85344)
						(xy -0.13716 0.82804) (xy -0.1524 0.8001) (xy -0.16256 0.76835) (xy -0.1651 0.7366) (xy -0.1651 0.44958)
						(xy -0.17272 0.44196) (xy -0.19812 0.4064) (xy -0.2032 0.39624) (xy -0.20701 0.38735) (xy -0.21209 0.37719)
						(xy -0.2159 0.36703) (xy -0.21844 0.35687) (xy -0.22225 0.34544) (xy -0.22352 0.33528) (xy -0.22606 0.32512)
						(xy -0.22733 0.31369) (xy -0.22733 0.30353) (xy -0.2286 0.2921) (xy -0.22733 0.28067) (xy -0.22733 0.27051)
						(xy -0.22606 0.25908) (xy -0.22352 0.24892) (xy -0.22225 0.23876) (xy -0.21844 0.22733) (xy -0.2159 0.21717)
						(xy -0.21209 0.20701) (xy -0.20701 0.19685) (xy -0.2032 0.18796) (xy -0.19812 0.1778) (xy -0.17272 0.14224)
						(xy -0.1651 0.13462) (xy -0.1651 -0.7366) (xy -0.16256 -0.76835) (xy -0.1524 -0.8001) (xy -0.13716 -0.82804)
						(xy -0.11684 -0.85344) (xy -0.09144 -0.87376) (xy -0.0635 -0.889) (xy -0.03175 -0.89916) (xy 0 -0.9017)
						(xy 0.03175 -0.89916) (xy 0.0635 -0.889) (xy 0.09144 -0.87376) (xy 0.11684 -0.85344) (xy 0.13716 -0.82804)
						(xy 0.1524 -0.8001) (xy 0.16256 -0.76835) (xy 0.1651 -0.7366) (xy 0.1651 0.13462) (xy 0.17272 0.14224)
						(xy 0.19812 0.1778) (xy 0.2032 0.18796) (xy 0.20701 0.19685) (xy 0.21209 0.20701) (xy 0.2159 0.21717)
						(xy 0.21844 0.22733) (xy 0.22225 0.23876) (xy 0.22352 0.24892) (xy 0.22606 0.25908) (xy 0.22733 0.27051)
						(xy 0.22733 0.28067) (xy 0.2286 0.2921) (xy 0.22733 0.30353) (xy 0.22733 0.31369) (xy 0.22606 0.32512)
						(xy 0.22352 0.33528) (xy 0.22225 0.34544) (xy 0.21844 0.35687) (xy 0.2159 0.36703) (xy 0.21209 0.37719)
						(xy 0.20701 0.38735) (xy 0.2032 0.39624) (xy 0.19812 0.4064) (xy 0.17272 0.44196) (xy 0.1651 0.44958)
						(xy 0.1651 0.7366) (xy 0.16256 0.76835) (xy 0.1524 0.8001) (xy 0.13716 0.82804) (xy 0.11684 0.85344)
						(xy 0.09144 0.87376) (xy 0.0635 0.889) (xy 0.03175 0.89916)
					)
					(width 0)
					(fill yes)
				)
			)
		)
		(pad "139" smd custom
			(at 12.15009 4.106672 180)
			(size 0.1143 0.1143)
			(layers "F.Cu" "F.Mask" "F.Paste")
			(net "M_A_DQS_DN4")
			(options
				(clearance outline)
				(anchor circle)
			)
			(primitives
				(gr_poly
					(pts
						(xy 0 0.9017) (xy -0.03175 0.89916) (xy -0.0635 0.889) (xy -0.09144 0.87376) (xy -0.11684 0.85344)
						(xy -0.13716 0.82804) (xy -0.1524 0.8001) (xy -0.16256 0.76835) (xy -0.1651 0.7366) (xy -0.1651 0.11938)
						(xy -0.17272 0.11176) (xy -0.19812 0.0762) (xy -0.2032 0.06604) (xy -0.20701 0.05715) (xy -0.21209 0.04699)
						(xy -0.2159 0.03683) (xy -0.21844 0.02667) (xy -0.22225 0.01524) (xy -0.22352 0.00508) (xy -0.22606 -0.00508)
						(xy -0.22733 -0.01651) (xy -0.22733 -0.02667) (xy -0.2286 -0.0381) (xy -0.22733 -0.04953) (xy -0.22733 -0.05969)
						(xy -0.22606 -0.07112) (xy -0.22352 -0.08128) (xy -0.22225 -0.09144) (xy -0.21844 -0.10287) (xy -0.2159 -0.11303)
						(xy -0.21209 -0.12319) (xy -0.20701 -0.13335) (xy -0.2032 -0.14224) (xy -0.19812 -0.1524) (xy -0.17272 -0.18796)
						(xy -0.1651 -0.19558) (xy -0.1651 -0.7366) (xy -0.16256 -0.76835) (xy -0.1524 -0.8001) (xy -0.13716 -0.82804)
						(xy -0.11684 -0.85344) (xy -0.09144 -0.87376) (xy -0.0635 -0.889) (xy -0.03175 -0.89916) (xy 0 -0.9017)
						(xy 0.03175 -0.89916) (xy 0.0635 -0.889) (xy 0.09144 -0.87376) (xy 0.11684 -0.85344) (xy 0.13716 -0.82804)
						(xy 0.1524 -0.8001) (xy 0.16256 -0.76835) (xy 0.1651 -0.7366) (xy 0.1651 -0.19685) (xy 0.17272 -0.18923)
						(xy 0.17907 -0.18034) (xy 0.18669 -0.17145) (xy 0.19177 -0.16256) (xy 0.19812 -0.15367) (xy 0.20828 -0.13335)
						(xy 0.21971 -0.10287) (xy 0.22225 -0.09271) (xy 0.22479 -0.08128) (xy 0.22606 -0.07112) (xy 0.2286 -0.05969)
						(xy 0.2286 -0.01651) (xy 0.22606 -0.00508) (xy 0.22479 0.00508) (xy 0.22225 0.01651) (xy 0.21971 0.02667)
						(xy 0.20828 0.05715) (xy 0.19812 0.07747) (xy 0.19177 0.08636) (xy 0.18669 0.09525) (xy 0.17907 0.10414)
						(xy 0.17272 0.11303) (xy 0.1651 0.12065) (xy 0.1651 0.7366) (xy 0.16256 0.76835) (xy 0.1524 0.8001)
						(xy 0.13716 0.82804) (xy 0.11684 0.85344) (xy 0.09144 0.87376) (xy 0.0635 0.889) (xy 0.03175 0.89916)
					)
					(width 0)
					(fill yes)
				)
			)
		)
	)
)
